(kicad_pcb
	(version 20260206)
	(generator "pcbnew")
	(generator_version "10.0")
	(general
		(thickness 1.6)
		(legacy_teardrops no)
	)
	(paper "A4")
	(title_block
		(title "01162023_DA0F0TEBIF0_F0T_Expander_BD_F_brd_V02_OCP.brd")
		(comment 1 "Grand Teton / footprints 6942-6948 of 9728")
	)
	(layers
		(0 "F.Cu" signal "TOP")
		(4 "In1.Cu" signal "GND")
		(6 "In2.Cu" signal "VCC")
		(8 "In3.Cu" signal "VCC1")
		(10 "In4.Cu" signal "GND1")
		(12 "In5.Cu" signal "IN1")
		(14 "In6.Cu" signal "GND2")
		(16 "In7.Cu" signal "IN2")
		(18 "In8.Cu" signal "GND3")
		(20 "In9.Cu" signal "IN3")
		(22 "In10.Cu" signal "GND4")
		(24 "In11.Cu" signal "IN4")
		(26 "In12.Cu" signal "GND5")
		(28 "In13.Cu" signal "IN5")
		(30 "In14.Cu" signal "GND6")
		(32 "In15.Cu" signal "IN6")
		(34 "In16.Cu" signal "GND7")
		(2 "B.Cu" signal "BOTTOM")
		(9 "F.Adhes" user "F.Adhesive")
		(11 "B.Adhes" user "B.Adhesive")
		(13 "F.Paste" user "Package Geometry/Pastemask Top")
		(15 "B.Paste" user "Package Geometry/Pastemask Bottom")
		(5 "F.SilkS" user "Ref Des/Silkscreen Top")
		(7 "B.SilkS" user "Ref Des/Silkscreen Bottom")
		(1 "F.Mask" user "Board Geometry/Soldermask Top")
		(3 "B.Mask" user "Board Geometry/Soldermask Bottom")
		(17 "Dwgs.User" user "User.Drawings")
		(19 "Cmts.User" user "User.Comments")
		(21 "Eco1.User" user "User.Eco1")
		(23 "Eco2.User" user "User.Eco2")
		(25 "Edge.Cuts" user "Board Geometry/Outline")
		(27 "Margin" user)
		(31 "F.CrtYd" user "Package Geometry/Place Bound Top")
		(29 "B.CrtYd" user "Package Geometry/Place Bound Bottom")
		(35 "F.Fab" user "Ref Des/Assembly Top")
		(33 "B.Fab" user "Ref Des/Assembly Bottom")
	)
	(footprint ""
		(layer "F.Cu")
		(at 237.963964 -254.18542 -90)
		(property "Reference" "C4340"
			(at 0 0 270)
			(layer "F.SilkS")
			(hide yes)
			(effects
				(font
					(size 1.27 1.27)
				)
			)
		)
		(property "Value" ""
			(at 0 0 270)
			(layer "F.Fab")
			(effects
				(font
					(size 1.27 1.27)
				)
			)
		)
		(duplicate_pad_numbers_are_jumpers no)
		(fp_line
			(start -1.2954 0.5842)
			(end -1.2954 -0.5842)
			(stroke
				(width 0.1524)
				(type default)
			)
			(layer "F.SilkS")
		)
		(fp_line
			(start 1.2954 0.5842)
			(end -1.2954 0.5842)
			(stroke
				(width 0.1524)
				(type default)
			)
			(layer "F.SilkS")
		)
		(fp_line
			(start -1.2954 -0.5842)
			(end 1.2954 -0.5842)
			(stroke
				(width 0.1524)
				(type default)
			)
			(layer "F.SilkS")
		)
		(fp_line
			(start 1.2954 -0.5842)
			(end 1.2954 0.5842)
			(stroke
				(width 0.1524)
				(type default)
			)
			(layer "F.SilkS")
		)
		(fp_line
			(start -0.8636 0.4572)
			(end -0.8636 0.4064)
			(stroke
				(width 0.1)
				(type default)
			)
			(layer "F.Fab")
		)
		(fp_line
			(start 0.8636 0.4572)
			(end -0.8636 0.4572)
			(stroke
				(width 0.1)
				(type default)
			)
			(layer "F.Fab")
		)
		(fp_line
			(start -1.1938 0.4064)
			(end -1.1938 -0.4064)
			(stroke
				(width 0.1)
				(type default)
			)
			(layer "F.Fab")
		)
		(fp_line
			(start -0.8636 0.4064)
			(end -1.1938 0.4064)
			(stroke
				(width 0.1)
				(type default)
			)
			(layer "F.Fab")
		)
		(fp_line
			(start 0.8636 0.4064)
			(end 0.8636 0.4572)
			(stroke
				(width 0.1)
				(type default)
			)
			(layer "F.Fab")
		)
		(fp_line
			(start 1.1938 0.4064)
			(end 0.8636 0.4064)
			(stroke
				(width 0.1)
				(type default)
			)
			(layer "F.Fab")
		)
		(fp_line
			(start -1.1938 -0.4064)
			(end -0.8636 -0.4064)
			(stroke
				(width 0.1)
				(type default)
			)
			(layer "F.Fab")
		)
		(fp_line
			(start -0.8636 -0.4064)
			(end -0.8636 -0.4572)
			(stroke
				(width 0.1)
				(type default)
			)
			(layer "F.Fab")
		)
		(fp_line
			(start 0.8636 -0.4064)
			(end 1.1938 -0.4064)
			(stroke
				(width 0.1)
				(type default)
			)
			(layer "F.Fab")
		)
		(fp_line
			(start 1.1938 -0.4064)
			(end 1.1938 0.4064)
			(stroke
				(width 0.1)
				(type default)
			)
			(layer "F.Fab")
		)
		(fp_line
			(start -0.8636 -0.4572)
			(end 0.8636 -0.4572)
			(stroke
				(width 0.1)
				(type default)
			)
			(layer "F.Fab")
		)
		(fp_line
			(start 0.8636 -0.4572)
			(end 0.8636 -0.4064)
			(stroke
				(width 0.1)
				(type default)
			)
			(layer "F.Fab")
		)
		(pad "1" smd rect
			(at -0.7366 0 180)
			(size 0.7112 0.8128)
			(layers "F.Cu" "F.Mask" "F.Paste")
			(net "P1V25_SERDES_VDDPLL_PEX2_C2")
		)
		(pad "2" smd rect
			(at 0.7366 0 180)
			(size 0.7112 0.8128)
			(layers "F.Cu" "F.Mask" "F.Paste")
			(net "GND")
		)
	)
	(footprint ""
		(layer "F.Cu")
		(at 384.938524 -123.71324)
		(property "Reference" "C677"
			(at 0 0 0)
			(layer "F.SilkS")
			(hide yes)
			(effects
				(font
					(size 1.27 1.27)
				)
			)
		)
		(property "Value" ""
			(at 0 0 0)
			(layer "F.Fab")
			(effects
				(font
					(size 1.27 1.27)
				)
			)
		)
		(duplicate_pad_numbers_are_jumpers no)
		(fp_line
			(start -0.299974 -0.150114)
			(end 0.299974 -0.150114)
			(stroke
				(width 0.1)
				(type default)
			)
			(layer "F.Fab")
		)
		(fp_line
			(start -0.299974 0.150114)
			(end -0.299974 -0.150114)
			(stroke
				(width 0.1)
				(type default)
			)
			(layer "F.Fab")
		)
		(fp_line
			(start 0.299974 -0.150114)
			(end 0.299974 0.150114)
			(stroke
				(width 0.1)
				(type default)
			)
			(layer "F.Fab")
		)
		(fp_line
			(start 0.299974 0.150114)
			(end -0.299974 0.150114)
			(stroke
				(width 0.1)
				(type default)
			)
			(layer "F.Fab")
		)
		(pad "1" smd rect
			(at -0.2667 0)
			(size 0.3048 0.381)
			(layers "F.Cu" "F.Mask" "F.Paste")
			(net "P5E_PEX3_STN1_TX_DN<26>")
		)
		(pad "2" smd rect
			(at 0.2667 0)
			(size 0.3048 0.381)
			(layers "F.Cu" "F.Mask" "F.Paste")
			(net "P5E_PEX3_STN1_TX_C_DN<26>")
		)
	)
	(footprint ""
		(layer "F.Cu")
		(at 187.346844 -38.49116 180)
		(property "Reference" "R6077"
			(at 0 0 180)
			(layer "F.SilkS")
			(hide yes)
			(effects
				(font
					(size 1.27 1.27)
				)
			)
		)
		(property "Value" ""
			(at 0 0 180)
			(layer "F.Fab")
			(effects
				(font
					(size 1.27 1.27)
				)
			)
		)
		(duplicate_pad_numbers_are_jumpers no)
		(fp_line
			(start 0.7874 0.4064)
			(end -0.7874 0.4064)
			(stroke
				(width 0.1524)
				(type default)
			)
			(layer "F.SilkS")
		)
		(fp_line
			(start 0.7874 -0.4064)
			(end 0.7874 0.4064)
			(stroke
				(width 0.1524)
				(type default)
			)
			(layer "F.SilkS")
		)
		(fp_line
			(start -0.7874 0.4064)
			(end -0.7874 -0.4064)
			(stroke
				(width 0.1524)
				(type default)
			)
			(layer "F.SilkS")
		)
		(fp_line
			(start -0.7874 -0.4064)
			(end 0.7874 -0.4064)
			(stroke
				(width 0.1524)
				(type default)
			)
			(layer "F.SilkS")
		)
		(fp_line
			(start 0.67945 0.3048)
			(end 0.120396 0.3048)
			(stroke
				(width 0.1)
				(type default)
			)
			(layer "F.Fab")
		)
		(fp_line
			(start 0.67945 -0.3048)
			(end 0.67945 0.3048)
			(stroke
				(width 0.1)
				(type default)
			)
			(layer "F.Fab")
		)
		(fp_line
			(start 0.12065 -0.2794)
			(end 0.12065 -0.3048)
			(stroke
				(width 0.1)
				(type default)
			)
			(layer "F.Fab")
		)
		(fp_line
			(start 0.12065 -0.3048)
			(end 0.67945 -0.3048)
			(stroke
				(width 0.1)
				(type default)
			)
			(layer "F.Fab")
		)
		(fp_line
			(start 0.120396 0.3048)
			(end 0.120396 0.2794)
			(stroke
				(width 0.1)
				(type default)
			)
			(layer "F.Fab")
		)
		(fp_line
			(start 0.120396 0.2794)
			(end -0.12065 0.2794)
			(stroke
				(width 0.1)
				(type default)
			)
			(layer "F.Fab")
		)
		(fp_line
			(start -0.12065 0.3048)
			(end -0.67945 0.3048)
			(stroke
				(width 0.1)
				(type default)
			)
			(layer "F.Fab")
		)
		(fp_line
			(start -0.12065 0.2794)
			(end -0.12065 0.3048)
			(stroke
				(width 0.1)
				(type default)
			)
			(layer "F.Fab")
		)
		(fp_line
			(start -0.12065 -0.2794)
			(end 0.12065 -0.2794)
			(stroke
				(width 0.1)
				(type default)
			)
			(layer "F.Fab")
		)
		(fp_line
			(start -0.12065 -0.305054)
			(end -0.12065 -0.2794)
			(stroke
				(width 0.1)
				(type default)
			)
			(layer "F.Fab")
		)
		(fp_line
			(start -0.67945 0.3048)
			(end -0.67945 -0.305054)
			(stroke
				(width 0.1)
				(type default)
			)
			(layer "F.Fab")
		)
		(fp_line
			(start -0.67945 -0.305054)
			(end -0.12065 -0.305054)
			(stroke
				(width 0.1)
				(type default)
			)
			(layer "F.Fab")
		)
		(pad "1" smd circle
			(at -0.40005 0 180)
			(size 0 0)
			(layers "F.Cu" "F.Mask" "F.Paste")
			(net "P3V3_SSD7_PG_G1")
		)
		(pad "2" smd circle
			(at 0.40005 0 180)
			(size 0 0)
			(layers "F.Cu" "F.Mask" "F.Paste")
			(net "GND")
		)
	)
	(footprint ""
		(layer "F.Cu")
		(at 238.891064 -227.73767 -90)
		(property "Reference" "R6593"
			(at 0 0 270)
			(layer "F.SilkS")
			(hide yes)
			(effects
				(font
					(size 1.27 1.27)
				)
			)
		)
		(property "Value" ""
			(at 0 0 270)
			(layer "F.Fab")
			(effects
				(font
					(size 1.27 1.27)
				)
			)
		)
		(duplicate_pad_numbers_are_jumpers no)
		(fp_line
			(start -0.7874 0.4064)
			(end -0.7874 -0.4064)
			(stroke
				(width 0.1524)
				(type default)
			)
			(layer "F.SilkS")
		)
		(fp_line
			(start 0.7874 0.4064)
			(end -0.7874 0.4064)
			(stroke
				(width 0.1524)
				(type default)
			)
			(layer "F.SilkS")
		)
		(fp_line
			(start -0.7874 -0.4064)
			(end 0.7874 -0.4064)
			(stroke
				(width 0.1524)
				(type default)
			)
			(layer "F.SilkS")
		)
		(fp_line
			(start 0.7874 -0.4064)
			(end 0.7874 0.4064)
			(stroke
				(width 0.1524)
				(type default)
			)
			(layer "F.SilkS")
		)
		(fp_line
			(start -0.67945 0.3048)
			(end -0.67945 -0.305054)
			(stroke
				(width 0.1)
				(type default)
			)
			(layer "F.Fab")
		)
		(fp_line
			(start -0.12065 0.3048)
			(end -0.67945 0.3048)
			(stroke
				(width 0.1)
				(type default)
			)
			(layer "F.Fab")
		)
		(fp_line
			(start 0.120396 0.3048)
			(end 0.120396 0.2794)
			(stroke
				(width 0.1)
				(type default)
			)
			(layer "F.Fab")
		)
		(fp_line
			(start 0.67945 0.3048)
			(end 0.120396 0.3048)
			(stroke
				(width 0.1)
				(type default)
			)
			(layer "F.Fab")
		)
		(fp_line
			(start -0.12065 0.2794)
			(end -0.12065 0.3048)
			(stroke
				(width 0.1)
				(type default)
			)
			(layer "F.Fab")
		)
		(fp_line
			(start 0.120396 0.2794)
			(end -0.12065 0.2794)
			(stroke
				(width 0.1)
				(type default)
			)
			(layer "F.Fab")
		)
		(fp_line
			(start -0.12065 -0.2794)
			(end 0.12065 -0.2794)
			(stroke
				(width 0.1)
				(type default)
			)
			(layer "F.Fab")
		)
		(fp_line
			(start 0.12065 -0.2794)
			(end 0.12065 -0.3048)
			(stroke
				(width 0.1)
				(type default)
			)
			(layer "F.Fab")
		)
		(fp_line
			(start 0.12065 -0.3048)
			(end 0.67945 -0.3048)
			(stroke
				(width 0.1)
				(type default)
			)
			(layer "F.Fab")
		)
		(fp_line
			(start 0.67945 -0.3048)
			(end 0.67945 0.3048)
			(stroke
				(width 0.1)
				(type default)
			)
			(layer "F.Fab")
		)
		(fp_line
			(start -0.67945 -0.305054)
			(end -0.12065 -0.305054)
			(stroke
				(width 0.1)
				(type default)
			)
			(layer "F.Fab")
		)
		(fp_line
			(start -0.12065 -0.305054)
			(end -0.12065 -0.2794)
			(stroke
				(width 0.1)
				(type default)
			)
			(layer "F.Fab")
		)
		(pad "1" smd circle
			(at -0.40005 0 270)
			(size 0 0)
			(layers "F.Cu" "F.Mask" "F.Paste")
			(net "P1V8_PLL0_PEX2")
		)
		(pad "2" smd circle
			(at 0.40005 0 270)
			(size 0 0)
			(layers "F.Cu" "F.Mask" "F.Paste")
			(net "P1V8_PLL0_PEX2_SCALED")
		)
	)
	(footprint ""
		(layer "F.Cu")
		(at 344.784172 -277.644352)
		(property "Reference" "PC142"
			(at 0 0 0)
			(layer "F.SilkS")
			(hide yes)
			(effects
				(font
					(size 1.27 1.27)
				)
			)
		)
		(property "Value" ""
			(at 0 0 0)
			(layer "F.Fab")
			(effects
				(font
					(size 1.27 1.27)
				)
			)
		)
		(duplicate_pad_numbers_are_jumpers no)
		(fp_line
			(start -1.524 -0.762)
			(end 1.524 -0.762)
			(stroke
				(width 0.1524)
				(type default)
			)
			(layer "F.SilkS")
		)
		(fp_line
			(start -1.524 0.762)
			(end -1.524 -0.762)
			(stroke
				(width 0.1524)
				(type default)
			)
			(layer "F.SilkS")
		)
		(fp_line
			(start 1.524 -0.762)
			(end 1.524 0.762)
			(stroke
				(width 0.1524)
				(type default)
			)
			(layer "F.SilkS")
		)
		(fp_line
			(start 1.524 0.762)
			(end -1.524 0.762)
			(stroke
				(width 0.1524)
				(type default)
			)
			(layer "F.SilkS")
		)
		(fp_line
			(start -1.1049 -0.724916)
			(end -1.1049 0.724916)
			(stroke
				(width 0.1)
				(type default)
			)
			(layer "F.Fab")
		)
		(fp_line
			(start -1.1049 0.724916)
			(end 1.1049 0.724916)
			(stroke
				(width 0.1)
				(type default)
			)
			(layer "F.Fab")
		)
		(fp_line
			(start 1.1049 -0.724916)
			(end -1.1049 -0.724916)
			(stroke
				(width 0.1)
				(type default)
			)
			(layer "F.Fab")
		)
		(fp_line
			(start 1.1049 0.724916)
			(end 1.1049 -0.724916)
			(stroke
				(width 0.1)
				(type default)
			)
			(layer "F.Fab")
		)
		(pad "1" smd rect
			(at -0.889 0 180)
			(size 1.016 1.27)
			(layers "F.Cu" "F.Mask" "F.Paste")
			(net "SW_P12V_P0V8_PEX2_FLT")
		)
		(pad "2" smd rect
			(at 0.889 0 180)
			(size 1.016 1.27)
			(layers "F.Cu" "F.Mask" "F.Paste")
			(net "GND")
		)
	)
	(footprint ""
		(layer "F.Cu")
		(at 428.79518 -35.48253)
		(property "Reference" "U396"
			(at -2.53111 0.73533 90)
			(unlocked yes)
			(layer "F.SilkS")
			(effects
				(font
					(size 0.7874 0.5842)
					(thickness 0.1524)
				)
				(justify left)
			)
		)
		(property "Value" ""
			(at 0 0 0)
			(layer "F.Fab")
			(effects
				(font
					(size 1.27 1.27)
				)
			)
		)
		(duplicate_pad_numbers_are_jumpers no)
		(fp_line
			(start -1.3462 -1.1938)
			(end -1.3462 1.1684)
			(stroke
				(width 0.1524)
				(type default)
			)
			(layer "F.SilkS")
		)
		(fp_line
			(start -1.3462 1.1938)
			(end 1.3462 1.1938)
			(stroke
				(width 0.1524)
				(type default)
			)
			(layer "F.SilkS")
		)
		(fp_line
			(start 1.3462 -1.1938)
			(end -1.3462 -1.1938)
			(stroke
				(width 0.1524)
				(type default)
			)
			(layer "F.SilkS")
		)
		(fp_line
			(start 1.3462 1.1938)
			(end 1.3462 -1.1938)
			(stroke
				(width 0.1524)
				(type default)
			)
			(layer "F.SilkS")
		)
		(fp_poly
			(pts
				(xy -1.447038 -0.760476) (xy -2.052066 -0.457962) (xy -2.052066 -1.06299)
			)
			(stroke
				(width 0)
				(type default)
			)
			(fill yes)
			(layer "F.SilkS")
		)
		(fp_line
			(start -0.674878 -1.124966)
			(end -0.674878 1.124966)
			(stroke
				(width 0.1)
				(type default)
			)
			(layer "F.Fab")
		)
		(fp_line
			(start -0.674878 1.124966)
			(end 0.674878 1.124966)
			(stroke
				(width 0.1)
				(type default)
			)
			(layer "F.Fab")
		)
		(fp_line
			(start 0.674878 -1.124966)
			(end -0.674878 -1.124966)
			(stroke
				(width 0.1)
				(type default)
			)
			(layer "F.Fab")
		)
		(fp_line
			(start 0.674878 1.124966)
			(end 0.674878 -1.124966)
			(stroke
				(width 0.1)
				(type default)
			)
			(layer "F.Fab")
		)
		(fp_poly
			(pts
				(xy -1.447038 -0.760476) (xy -2.052066 -0.457962) (xy -2.052066 -1.06299)
			)
			(stroke
				(width 0)
				(type default)
			)
			(fill yes)
			(layer "F.Fab")
		)
		(pad "1" smd rect
			(at -0.899922 -0.750062)
			(size 0.6096 0.6096)
			(layers "F.Cu" "F.Mask" "F.Paste")
			(net "PWRGD_P3V3_SSD15_R")
		)
		(pad "2" smd rect
			(at -0.899922 0 90)
			(size 0.4064 0.6096)
			(layers "F.Cu" "F.Mask" "F.Paste")
			(net "RST_SMB_SSD15_N")
		)
		(pad "3" smd rect
			(at -0.899922 0.750062)
			(size 0.6096 0.6096)
			(layers "F.Cu" "F.Mask" "F.Paste")
			(net "GND")
		)
		(pad "4" smd rect
			(at 0.899922 0.750062)
			(size 0.6096 0.6096)
			(layers "F.Cu" "F.Mask" "F.Paste")
			(net "RST_SMB_SSD15_ISO_N")
		)
		(pad "5" smd rect
			(at 0.899922 -0.750062)
			(size 0.6096 0.6096)
			(layers "F.Cu" "F.Mask" "F.Paste")
			(net "P3V3_AUX")
		)
	)
	(footprint ""
		(layer "F.Cu")
		(at 227.773484 -309.211218 90)
		(property "Reference" "PR173"
			(at 0 0 90)
			(layer "F.SilkS")
			(hide yes)
			(effects
				(font
					(size 1.27 1.27)
				)
			)
		)
		(property "Value" ""
			(at 0 0 90)
			(layer "F.Fab")
			(effects
				(font
					(size 1.27 1.27)
				)
			)
		)
		(duplicate_pad_numbers_are_jumpers no)
		(fp_line
			(start 0.7874 -0.4064)
			(end 0.7874 0.4064)
			(stroke
				(width 0.1524)
				(type default)
			)
			(layer "F.SilkS")
		)
		(fp_line
			(start -0.7874 -0.4064)
			(end 0.7874 -0.4064)
			(stroke
				(width 0.1524)
				(type default)
			)
			(layer "F.SilkS")
		)
		(fp_line
			(start 0.7874 0.4064)
			(end -0.7874 0.4064)
			(stroke
				(width 0.1524)
				(type default)
			)
			(layer "F.SilkS")
		)
		(fp_line
			(start -0.7874 0.4064)
			(end -0.7874 -0.4064)
			(stroke
				(width 0.1524)
				(type default)
			)
			(layer "F.SilkS")
		)
		(fp_line
			(start -0.12065 -0.305054)
			(end -0.12065 -0.2794)
			(stroke
				(width 0.1)
				(type default)
			)
			(layer "F.Fab")
		)
		(fp_line
			(start -0.67945 -0.305054)
			(end -0.12065 -0.305054)
			(stroke
				(width 0.1)
				(type default)
			)
			(layer "F.Fab")
		)
		(fp_line
			(start 0.67945 -0.3048)
			(end 0.67945 0.3048)
			(stroke
				(width 0.1)
				(type default)
			)
			(layer "F.Fab")
		)
		(fp_line
			(start 0.12065 -0.3048)
			(end 0.67945 -0.3048)
			(stroke
				(width 0.1)
				(type default)
			)
			(layer "F.Fab")
		)
		(fp_line
			(start 0.12065 -0.2794)
			(end 0.12065 -0.3048)
			(stroke
				(width 0.1)
				(type default)
			)
			(layer "F.Fab")
		)
		(fp_line
			(start -0.12065 -0.2794)
			(end 0.12065 -0.2794)
			(stroke
				(width 0.1)
				(type default)
			)
			(layer "F.Fab")
		)
		(fp_line
			(start 0.120396 0.2794)
			(end -0.12065 0.2794)
			(stroke
				(width 0.1)
				(type default)
			)
			(layer "F.Fab")
		)
		(fp_line
			(start -0.12065 0.2794)
			(end -0.12065 0.3048)
			(stroke
				(width 0.1)
				(type default)
			)
			(layer "F.Fab")
		)
		(fp_line
			(start 0.67945 0.3048)
			(end 0.120396 0.3048)
			(stroke
				(width 0.1)
				(type default)
			)
			(layer "F.Fab")
		)
		(fp_line
			(start 0.120396 0.3048)
			(end 0.120396 0.2794)
			(stroke
				(width 0.1)
				(type default)
			)
			(layer "F.Fab")
		)
		(fp_line
			(start -0.12065 0.3048)
			(end -0.67945 0.3048)
			(stroke
				(width 0.1)
				(type default)
			)
			(layer "F.Fab")
		)
		(fp_line
			(start -0.67945 0.3048)
			(end -0.67945 -0.305054)
			(stroke
				(width 0.1)
				(type default)
			)
			(layer "F.Fab")
		)
		(pad "1" smd circle
			(at -0.40005 0 90)
			(size 0 0)
			(layers "F.Cu" "F.Mask" "F.Paste")
			(net "SH_P1V25_PEX1_FB_N")
		)
		(pad "2" smd circle
			(at 0.40005 0 90)
			(size 0 0)
			(layers "F.Cu" "F.Mask" "F.Paste")
			(net "P1V25_PEX1_FB")
		)
	)
)
